# T6G (Grand Teton) — schematic netlist excerpt (pin names and nets, part order shuffled) for the footprints in the layout excerpt that follows; sources: Cadence DE-HDL packaged netlist, KiCad conversion of 04192023_DAF0TMB3IC0_F0TG_MB_C_brd_V02_OCP.brd

R902  Q_RES  1K 1% CHIP  pkg 0201LF  page 353 : A = P1V8_CPU1_RT_1D ; B = RT_CPU1_P3_ADDR3
PR431  Q_RES  8.87K 1% EMPTY  pkg 0402LF  page 196 : A = GND ; B = PVDDCR_CPU0_P0_LSET6
C9004  Q_CAP  1UF 25V 10% EMPTY  pkg C0402  page 268 : A = U206_VS ; B = GND

(kicad_pcb
	(version 20260206)
	(generator "pcbnew")
	(generator_version "10.0")
	(general
		(thickness 1.6)
		(legacy_teardrops no)
	)
	(paper "A4")
	(title_block
		(title "04192023_DAF0TMB3IC0_F0TG_MB_C_brd_V02_OCP.brd")
		(comment 1 "Grand Teton / footprints 3413-3415 of 8354")
	)
	(layers
		(0 "F.Cu" signal "TOP")
		(4 "In1.Cu" signal "GND")
		(6 "In2.Cu" signal "IN1")
		(8 "In3.Cu" signal "GND1")
		(10 "In4.Cu" signal "IN2")
		(12 "In5.Cu" signal "GND2")
		(14 "In6.Cu" signal "IN3")
		(16 "In7.Cu" signal "GND3")
		(18 "In8.Cu" signal "VCC")
		(20 "In9.Cu" signal "VCC1")
		(22 "In10.Cu" signal "GND4")
		(24 "In11.Cu" signal "IN4")
		(26 "In12.Cu" signal "GND5")
		(28 "In13.Cu" signal "IN5")
		(30 "In14.Cu" signal "GND6")
		(32 "In15.Cu" signal "IN6")
		(34 "In16.Cu" signal "GND7")
		(2 "B.Cu" signal "BOTTOM")
		(9 "F.Adhes" user "F.Adhesive")
		(11 "B.Adhes" user "B.Adhesive")
		(13 "F.Paste" user "Package Geometry/Pastemask Top")
		(15 "B.Paste" user "Package Geometry/Pastemask Bottom")
		(5 "F.SilkS" user "Ref Des/Silkscreen Top")
		(7 "B.SilkS" user "Ref Des/Silkscreen Bottom")
		(1 "F.Mask" user "Board Geometry/Soldermask Top")
		(3 "B.Mask" user "Board Geometry/Soldermask Bottom")
		(17 "Dwgs.User" user "User.Drawings")
		(19 "Cmts.User" user "User.Comments")
		(21 "Eco1.User" user "User.Eco1")
		(23 "Eco2.User" user "User.Eco2")
		(25 "Edge.Cuts" user "Board Geometry/Outline")
		(27 "Margin" user)
		(31 "F.CrtYd" user "Package Geometry/Place Bound Top")
		(29 "B.CrtYd" user "Package Geometry/Place Bound Bottom")
		(35 "F.Fab" user "Ref Des/Assembly Top")
		(33 "B.Fab" user "Ref Des/Assembly Bottom")
	)
	(footprint ""
		(layer "F.Cu")
		(at 349.032322 -155.927806)
		(property "Reference" "PR431"
			(at 0 0 0)
			(layer "F.SilkS")
			(hide yes)
			(effects
				(font
					(size 1.27 1.27)
				)
			)
		)
		(property "Value" ""
			(at 0 0 0)
			(layer "F.Fab")
			(effects
				(font
					(size 1.27 1.27)
				)
			)
		)
		(duplicate_pad_numbers_are_jumpers no)
		(fp_line
			(start -0.7874 -0.4064)
			(end 0.7874 -0.4064)
			(stroke
				(width 0.1524)
				(type default)
			)
			(layer "F.SilkS")
		)
		(fp_line
			(start -0.7874 0.4064)
			(end -0.7874 -0.4064)
			(stroke
				(width 0.1524)
				(type default)
			)
			(layer "F.SilkS")
		)
		(fp_line
			(start 0.7874 -0.4064)
			(end 0.7874 0.4064)
			(stroke
				(width 0.1524)
				(type default)
			)
			(layer "F.SilkS")
		)
		(fp_line
			(start 0.7874 0.4064)
			(end -0.7874 0.4064)
			(stroke
				(width 0.1524)
				(type default)
			)
			(layer "F.SilkS")
		)
		(fp_line
			(start -0.67945 -0.305054)
			(end -0.12065 -0.305054)
			(stroke
				(width 0.1)
				(type default)
			)
			(layer "F.Fab")
		)
		(fp_line
			(start -0.67945 0.3048)
			(end -0.67945 -0.305054)
			(stroke
				(width 0.1)
				(type default)
			)
			(layer "F.Fab")
		)
		(fp_line
			(start -0.12065 -0.305054)
			(end -0.12065 -0.2794)
			(stroke
				(width 0.1)
				(type default)
			)
			(layer "F.Fab")
		)
		(fp_line
			(start -0.12065 -0.2794)
			(end 0.12065 -0.2794)
			(stroke
				(width 0.1)
				(type default)
			)
			(layer "F.Fab")
		)
		(fp_line
			(start -0.12065 0.2794)
			(end -0.12065 0.3048)
			(stroke
				(width 0.1)
				(type default)
			)
			(layer "F.Fab")
		)
		(fp_line
			(start -0.12065 0.3048)
			(end -0.67945 0.3048)
			(stroke
				(width 0.1)
				(type default)
			)
			(layer "F.Fab")
		)
		(fp_line
			(start 0.120396 0.2794)
			(end -0.12065 0.2794)
			(stroke
				(width 0.1)
				(type default)
			)
			(layer "F.Fab")
		)
		(fp_line
			(start 0.120396 0.3048)
			(end 0.120396 0.2794)
			(stroke
				(width 0.1)
				(type default)
			)
			(layer "F.Fab")
		)
		(fp_line
			(start 0.12065 -0.3048)
			(end 0.67945 -0.3048)
			(stroke
				(width 0.1)
				(type default)
			)
			(layer "F.Fab")
		)
		(fp_line
			(start 0.12065 -0.2794)
			(end 0.12065 -0.3048)
			(stroke
				(width 0.1)
				(type default)
			)
			(layer "F.Fab")
		)
		(fp_line
			(start 0.67945 -0.3048)
			(end 0.67945 0.3048)
			(stroke
				(width 0.1)
				(type default)
			)
			(layer "F.Fab")
		)
		(fp_line
			(start 0.67945 0.3048)
			(end 0.120396 0.3048)
			(stroke
				(width 0.1)
				(type default)
			)
			(layer "F.Fab")
		)
		(pad "1" smd circle
			(at -0.40005 0)
			(size 0 0)
			(layers "F.Cu" "F.Mask" "F.Paste")
			(net "GND")
		)
		(pad "2" smd circle
			(at 0.40005 0)
			(size 0 0)
			(layers "F.Cu" "F.Mask" "F.Paste")
			(net "PVDDCR_CPU0_P0_LSET6")
		)
	)
	(footprint ""
		(layer "F.Cu")
		(at 138.981942 -385.5212 90)
		(property "Reference" "R902"
			(at 0 0 90)
			(layer "F.SilkS")
			(hide yes)
			(effects
				(font
					(size 1.27 1.27)
				)
			)
		)
		(property "Value" ""
			(at 0 0 90)
			(layer "F.Fab")
			(effects
				(font
					(size 1.27 1.27)
				)
			)
		)
		(duplicate_pad_numbers_are_jumpers no)
		(fp_line
			(start 0.32512 -0.175006)
			(end 0.32512 0.175006)
			(stroke
				(width 0.1)
				(type default)
			)
			(layer "F.Fab")
		)
		(fp_line
			(start -0.32512 -0.175006)
			(end 0.32512 -0.175006)
			(stroke
				(width 0.1)
				(type default)
			)
			(layer "F.Fab")
		)
		(fp_line
			(start 0.32512 0.175006)
			(end -0.32512 0.175006)
			(stroke
				(width 0.1)
				(type default)
			)
			(layer "F.Fab")
		)
		(fp_line
			(start -0.32512 0.175006)
			(end -0.32512 -0.175006)
			(stroke
				(width 0.1)
				(type default)
			)
			(layer "F.Fab")
		)
		(pad "1" smd rect
			(at -0.2667 0 90)
			(size 0.3048 0.381)
			(layers "F.Cu" "F.Mask" "F.Paste")
			(net "P1V8_CPU1_RT_1D")
		)
		(pad "2" smd rect
			(at 0.2667 0 270)
			(size 0.3048 0.381)
			(layers "F.Cu" "F.Mask" "F.Paste")
			(net "RT_CPU1_P3_ADDR3")
		)
	)
	(footprint ""
		(layer "F.Cu")
		(at 148.971 -116.713 -90)
		(property "Reference" "C9004"
			(at 0 0 270)
			(layer "F.SilkS")
			(hide yes)
			(effects
				(font
					(size 1.27 1.27)
				)
			)
		)
		(property "Value" ""
			(at 0 0 270)
			(layer "F.Fab")
			(effects
				(font
					(size 1.27 1.27)
				)
			)
		)
		(duplicate_pad_numbers_are_jumpers no)
		(fp_line
			(start -0.7874 0.4064)
			(end -0.7874 -0.4064)
			(stroke
				(width 0.1524)
				(type default)
			)
			(layer "F.SilkS")
		)
		(fp_line
			(start 0.7874 0.4064)
			(end -0.7874 0.4064)
			(stroke
				(width 0.1524)
				(type default)
			)
			(layer "F.SilkS")
		)
		(fp_line
			(start -0.7874 -0.4064)
			(end 0.7874 -0.4064)
			(stroke
				(width 0.1524)
				(type default)
			)
			(layer "F.SilkS")
		)
		(fp_line
			(start 0.7874 -0.4064)
			(end 0.7874 0.4064)
			(stroke
				(width 0.1524)
				(type default)
			)
			(layer "F.SilkS")
		)
		(fp_line
			(start -0.67945 0.3048)
			(end -0.67945 -0.305054)
			(stroke
				(width 0.1)
				(type default)
			)
			(layer "F.Fab")
		)
		(fp_line
			(start -0.12065 0.3048)
			(end -0.67945 0.3048)
			(stroke
				(width 0.1)
				(type default)
			)
			(layer "F.Fab")
		)
		(fp_line
			(start 0.120396 0.3048)
			(end 0.120396 0.2794)
			(stroke
				(width 0.1)
				(type default)
			)
			(layer "F.Fab")
		)
		(fp_line
			(start 0.67945 0.3048)
			(end 0.120396 0.3048)
			(stroke
				(width 0.1)
				(type default)
			)
			(layer "F.Fab")
		)
		(fp_line
			(start -0.12065 0.2794)
			(end -0.12065 0.3048)
			(stroke
				(width 0.1)
				(type default)
			)
			(layer "F.Fab")
		)
		(fp_line
			(start 0.120396 0.2794)
			(end -0.12065 0.2794)
			(stroke
				(width 0.1)
				(type default)
			)
			(layer "F.Fab")
		)
		(fp_line
			(start -0.12065 -0.2794)
			(end 0.12065 -0.2794)
			(stroke
				(width 0.1)
				(type default)
			)
			(layer "F.Fab")
		)
		(fp_line
			(start 0.12065 -0.2794)
			(end 0.12065 -0.3048)
			(stroke
				(width 0.1)
				(type default)
			)
			(layer "F.Fab")
		)
		(fp_line
			(start 0.12065 -0.3048)
			(end 0.67945 -0.3048)
			(stroke
				(width 0.1)
				(type default)
			)
			(layer "F.Fab")
		)
		(fp_line
			(start 0.67945 -0.3048)
			(end 0.67945 0.3048)
			(stroke
				(width 0.1)
				(type default)
			)
			(layer "F.Fab")
		)
		(fp_line
			(start -0.67945 -0.305054)
			(end -0.12065 -0.305054)
			(stroke
				(width 0.1)
				(type default)
			)
			(layer "F.Fab")
		)
		(fp_line
			(start -0.12065 -0.305054)
			(end -0.12065 -0.2794)
			(stroke
				(width 0.1)
				(type default)
			)
			(layer "F.Fab")
		)
		(pad "1" smd circle
			(at -0.40005 0 270)
			(size 0 0)
			(layers "F.Cu" "F.Mask" "F.Paste")
			(net "U206_VS")
		)
		(pad "2" smd circle
			(at 0.40005 0 270)
			(size 0 0)
			(layers "F.Cu" "F.Mask" "F.Paste")
			(net "GND")
		)
	)
)
